(kicad_pcb
	(version 20260206)
	(generator "pcbnew")
	(generator_version "10.0")
	(general
		(thickness 1.6)
		(legacy_teardrops no)
	)
	(paper "A4")
	(title_block
		(title "04192023_DAF0TMB3IC0_F0TG_MB_C_brd_V02_OCP.brd")
		(comment 1 "Grand Teton / footprint 3955 of 8354 (U25), pads 1648-1760 of 6102")
	)
	(layers
		(0 "F.Cu" signal "TOP")
		(4 "In1.Cu" signal "GND")
		(6 "In2.Cu" signal "IN1")
		(8 "In3.Cu" signal "GND1")
		(10 "In4.Cu" signal "IN2")
		(12 "In5.Cu" signal "GND2")
		(14 "In6.Cu" signal "IN3")
		(16 "In7.Cu" signal "GND3")
		(18 "In8.Cu" signal "VCC")
		(20 "In9.Cu" signal "VCC1")
		(22 "In10.Cu" signal "GND4")
		(24 "In11.Cu" signal "IN4")
		(26 "In12.Cu" signal "GND5")
		(28 "In13.Cu" signal "IN5")
		(30 "In14.Cu" signal "GND6")
		(32 "In15.Cu" signal "IN6")
		(34 "In16.Cu" signal "GND7")
		(2 "B.Cu" signal "BOTTOM")
		(9 "F.Adhes" user "F.Adhesive")
		(11 "B.Adhes" user "B.Adhesive")
		(13 "F.Paste" user "Package Geometry/Pastemask Top")
		(15 "B.Paste" user "Package Geometry/Pastemask Bottom")
		(5 "F.SilkS" user "Ref Des/Silkscreen Top")
		(7 "B.SilkS" user "Ref Des/Silkscreen Bottom")
		(1 "F.Mask" user "Board Geometry/Soldermask Top")
		(3 "B.Mask" user "Board Geometry/Soldermask Bottom")
		(17 "Dwgs.User" user "User.Drawings")
		(19 "Cmts.User" user "User.Comments")
		(21 "Eco1.User" user "User.Eco1")
		(23 "Eco2.User" user "User.Eco2")
		(25 "Edge.Cuts" user "Board Geometry/Outline")
		(27 "Margin" user)
		(31 "F.CrtYd" user "Package Geometry/Place Bound Top")
		(29 "B.CrtYd" user "Package Geometry/Place Bound Bottom")
		(35 "F.Fab" user "Ref Des/Assembly Top")
		(33 "B.Fab" user "Ref Des/Assembly Bottom")
	)
	(footprint ""
		(layer "F.Cu")
		(at 359.867962 -258.880102 180)
		(property "Reference" "U25"
			(at -45.78477 -62.086744 0)
			(unlocked yes)
			(layer "F.SilkS")
			(effects
				(font
					(size 0.7874 0.5842)
					(thickness 0.1524)
				)
			)
		)
		(property "Value" ""
			(at 0 0 180)
			(layer "F.Fab")
			(effects
				(font
					(size 1.27 1.27)
				)
			)
		)
		(duplicate_pad_numbers_are_jumpers no)
		(pad "BB74" smd circle
			(at 33.990026 -3.599942 180)
			(size 0.450088 0.450088)
			(layers "F.Cu" "F.Mask" "F.Paste")
			(net "M_A_CPU0_SA_CA<5>")
		)
		(pad "BC1" smd circle
			(at -34.159952 -2.789936 180)
			(size 0.450088 0.450088)
			(layers "F.Cu" "F.Mask" "F.Paste")
			(net "GND")
		)
		(pad "BC2" smd circle
			(at -33.219898 -2.789936 180)
			(size 0.450088 0.450088)
			(layers "F.Cu" "F.Mask" "F.Paste")
			(net "M_G_CPU0_CLK_DP<0>")
		)
		(pad "BC3" smd circle
			(at -32.280098 -2.789936 180)
			(size 0.450088 0.450088)
			(layers "F.Cu" "F.Mask" "F.Paste")
			(net "M_G_CPU0_SA_PAR")
		)
		(pad "BC4" smd circle
			(at -31.340044 -2.789936 180)
			(size 0.450088 0.450088)
			(layers "F.Cu" "F.Mask" "F.Paste")
			(net "GND")
		)
		(pad "BC5" smd circle
			(at -30.39999 -2.789936 180)
			(size 0.450088 0.450088)
			(layers "F.Cu" "F.Mask" "F.Paste")
			(net "M_K_CPU0_CLK_DP<0>")
		)
		(pad "BC6" smd circle
			(at -29.459936 -2.789936 180)
			(size 0.450088 0.450088)
			(layers "F.Cu" "F.Mask" "F.Paste")
			(net "GND")
		)
		(pad "BC7" smd circle
			(at -28.519882 -2.789936 180)
			(size 0.450088 0.450088)
			(layers "F.Cu" "F.Mask" "F.Paste")
			(net "M_K_CPU0_SA_PAR")
		)
		(pad "BC8" smd circle
			(at -27.580082 -2.789936 180)
			(size 0.450088 0.450088)
			(layers "F.Cu" "F.Mask" "F.Paste")
			(net "GND")
		)
		(pad "BC9" smd circle
			(at -26.640028 -2.789936 180)
			(size 0.450088 0.450088)
			(layers "F.Cu" "F.Mask" "F.Paste")
			(net "M_L_CPU0_CLK_DP<0>")
		)
		(pad "BC10" smd circle
			(at -25.699974 -2.789936 180)
			(size 0.450088 0.450088)
			(layers "F.Cu" "F.Mask" "F.Paste")
			(net "M_L_CPU0_SA_PAR")
		)
		(pad "BC11" smd circle
			(at -24.75992 -2.789936 180)
			(size 0.450088 0.450088)
			(layers "F.Cu" "F.Mask" "F.Paste")
			(net "GND")
		)
		(pad "BC12" smd circle
			(at -23.82012 -2.789936 180)
			(size 0.450088 0.450088)
			(layers "F.Cu" "F.Mask" "F.Paste")
			(net "M_H_CPU0_CLK_DP<0>")
		)
		(pad "BC13" smd circle
			(at -22.880066 -2.789936 180)
			(size 0.450088 0.450088)
			(layers "F.Cu" "F.Mask" "F.Paste")
			(net "GND")
		)
		(pad "BC14" smd circle
			(at -21.940012 -2.789936 180)
			(size 0.450088 0.450088)
			(layers "F.Cu" "F.Mask" "F.Paste")
			(net "M_H_CPU0_SA_PAR")
		)
		(pad "BC15" smd circle
			(at -20.999958 -2.789936 180)
			(size 0.450088 0.450088)
			(layers "F.Cu" "F.Mask" "F.Paste")
			(net "GND")
		)
		(pad "BC16" smd circle
			(at -20.059904 -2.789936 180)
			(size 0.450088 0.450088)
			(layers "F.Cu" "F.Mask" "F.Paste")
			(net "M_J_CPU0_CLK_DP<0>")
		)
		(pad "BC17" smd circle
			(at -19.120104 -2.789936 180)
			(size 0.450088 0.450088)
			(layers "F.Cu" "F.Mask" "F.Paste")
			(net "M_J_CPU0_SA_PAR")
		)
		(pad "BC18" smd circle
			(at -18.18005 -2.789936 180)
			(size 0.450088 0.450088)
			(layers "F.Cu" "F.Mask" "F.Paste")
			(net "GND")
		)
		(pad "BC19" smd circle
			(at -17.239996 -2.789936 180)
			(size 0.450088 0.450088)
			(layers "F.Cu" "F.Mask" "F.Paste")
			(net "M_I_CPU0_CLK_DP<0>")
		)
		(pad "BC20" smd circle
			(at -16.299942 -2.789936 180)
			(size 0.450088 0.450088)
			(layers "F.Cu" "F.Mask" "F.Paste")
			(net "GND")
		)
		(pad "BC21" smd circle
			(at -15.359888 -2.789936 180)
			(size 0.450088 0.450088)
			(layers "F.Cu" "F.Mask" "F.Paste")
			(net "M_I_CPU0_SA_PAR")
		)
		(pad "BC22" smd circle
			(at -14.420088 -2.789936 180)
			(size 0.450088 0.450088)
			(layers "F.Cu" "F.Mask" "F.Paste")
			(net "GND")
		)
		(pad "BC23" smd circle
			(at -13.480034 -2.789936 180)
			(size 0.450088 0.450088)
			(layers "F.Cu" "F.Mask" "F.Paste")
			(net "PVDDCR_SOC_P0")
		)
		(pad "BC24" smd circle
			(at -12.53998 -2.789936 180)
			(size 0.450088 0.450088)
			(layers "F.Cu" "F.Mask" "F.Paste")
			(net "GND")
		)
		(pad "BC25" smd circle
			(at -11.599926 -2.789936 180)
			(size 0.450088 0.450088)
			(layers "F.Cu" "F.Mask" "F.Paste")
			(net "PVDDCR_SOC_P0")
		)
		(pad "BC26" smd circle
			(at -10.659872 -2.789936 180)
			(size 0.450088 0.450088)
			(layers "F.Cu" "F.Mask" "F.Paste")
			(net "GND")
		)
		(pad "BC27" smd circle
			(at -9.720072 -2.789936 180)
			(size 0.450088 0.450088)
			(layers "F.Cu" "F.Mask" "F.Paste")
			(net "PVDDCR_SOC_P0")
		)
		(pad "BC28" smd circle
			(at -8.780018 -2.789936 180)
			(size 0.450088 0.450088)
			(layers "F.Cu" "F.Mask" "F.Paste")
			(net "GND")
		)
		(pad "BC48" smd circle
			(at 9.079992 -2.789936 180)
			(size 0.450088 0.450088)
			(layers "F.Cu" "F.Mask" "F.Paste")
			(net "PVDDCR_SOC_P0")
		)
		(pad "BC49" smd circle
			(at 10.020046 -2.789936 180)
			(size 0.450088 0.450088)
			(layers "F.Cu" "F.Mask" "F.Paste")
			(net "GND")
		)
		(pad "BC50" smd circle
			(at 10.9601 -2.789936 180)
			(size 0.450088 0.450088)
			(layers "F.Cu" "F.Mask" "F.Paste")
			(net "GND")
		)
		(pad "BC51" smd circle
			(at 11.8999 -2.789936 180)
			(size 0.450088 0.450088)
			(layers "F.Cu" "F.Mask" "F.Paste")
			(net "GND")
		)
		(pad "BC52" smd circle
			(at 12.839954 -2.789936 180)
			(size 0.450088 0.450088)
			(layers "F.Cu" "F.Mask" "F.Paste")
			(net "PVDD18_S5_P0")
		)
		(pad "BC53" smd circle
			(at 13.780008 -2.789936 180)
			(size 0.450088 0.450088)
			(layers "F.Cu" "F.Mask" "F.Paste")
			(net "GND")
		)
		(pad "BC54" smd circle
			(at 14.720062 -2.789936 180)
			(size 0.450088 0.450088)
			(layers "F.Cu" "F.Mask" "F.Paste")
			(net "PVDD18_S5_P0")
		)
		(pad "BC55" smd circle
			(at 15.660116 -2.789936 180)
			(size 0.450088 0.450088)
			(layers "F.Cu" "F.Mask" "F.Paste")
			(net "M_C_CPU0_SA_PAR")
		)
		(pad "BC56" smd circle
			(at 16.599916 -2.789936 180)
			(size 0.450088 0.450088)
			(layers "F.Cu" "F.Mask" "F.Paste")
			(net "GND")
		)
		(pad "BC57" smd circle
			(at 17.53997 -2.789936 180)
			(size 0.450088 0.450088)
			(layers "F.Cu" "F.Mask" "F.Paste")
			(net "M_C_CPU0_CLK_DP<0>")
		)
		(pad "BC58" smd circle
			(at 18.480024 -2.789936 180)
			(size 0.450088 0.450088)
			(layers "F.Cu" "F.Mask" "F.Paste")
			(net "GND")
		)
		(pad "BC59" smd circle
			(at 19.420078 -2.789936 180)
			(size 0.450088 0.450088)
			(layers "F.Cu" "F.Mask" "F.Paste")
			(net "M_D_CPU0_SA_PAR")
		)
		(pad "BC60" smd circle
			(at 20.359878 -2.789936 180)
			(size 0.450088 0.450088)
			(layers "F.Cu" "F.Mask" "F.Paste")
			(net "M_D_CPU0_CLK_DP<0>")
		)
		(pad "BC61" smd circle
			(at 21.299932 -2.789936 180)
			(size 0.450088 0.450088)
			(layers "F.Cu" "F.Mask" "F.Paste")
			(net "GND")
		)
		(pad "BC62" smd circle
			(at 22.239986 -2.789936 180)
			(size 0.450088 0.450088)
			(layers "F.Cu" "F.Mask" "F.Paste")
			(net "M_B_CPU0_SA_PAR")
		)
		(pad "BC63" smd circle
			(at 23.18004 -2.789936 180)
			(size 0.450088 0.450088)
			(layers "F.Cu" "F.Mask" "F.Paste")
			(net "GND")
		)
		(pad "BC64" smd circle
			(at 24.120094 -2.789936 180)
			(size 0.450088 0.450088)
			(layers "F.Cu" "F.Mask" "F.Paste")
			(net "M_B_CPU0_CLK_DP<0>")
		)
		(pad "BC65" smd circle
			(at 25.059894 -2.789936 180)
			(size 0.450088 0.450088)
			(layers "F.Cu" "F.Mask" "F.Paste")
			(net "GND")
		)
		(pad "BC66" smd circle
			(at 25.999948 -2.789936 180)
			(size 0.450088 0.450088)
			(layers "F.Cu" "F.Mask" "F.Paste")
			(net "M_F_CPU0_SA_PAR")
		)
		(pad "BC67" smd circle
			(at 26.940002 -2.789936 180)
			(size 0.450088 0.450088)
			(layers "F.Cu" "F.Mask" "F.Paste")
			(net "M_F_CPU0_CLK_DP<0>")
		)
		(pad "BC68" smd circle
			(at 27.880056 -2.789936 180)
			(size 0.450088 0.450088)
			(layers "F.Cu" "F.Mask" "F.Paste")
			(net "GND")
		)
		(pad "BC69" smd circle
			(at 28.82011 -2.789936 180)
			(size 0.450088 0.450088)
			(layers "F.Cu" "F.Mask" "F.Paste")
			(net "M_E_CPU0_SA_PAR")
		)
		(pad "BC70" smd circle
			(at 29.75991 -2.789936 180)
			(size 0.450088 0.450088)
			(layers "F.Cu" "F.Mask" "F.Paste")
			(net "GND")
		)
		(pad "BC71" smd circle
			(at 30.699964 -2.789936 180)
			(size 0.450088 0.450088)
			(layers "F.Cu" "F.Mask" "F.Paste")
			(net "M_E_CPU0_CLK_DP<0>")
		)
		(pad "BC72" smd circle
			(at 31.640018 -2.789936 180)
			(size 0.450088 0.450088)
			(layers "F.Cu" "F.Mask" "F.Paste")
			(net "GND")
		)
		(pad "BC73" smd circle
			(at 32.580072 -2.789936 180)
			(size 0.450088 0.450088)
			(layers "F.Cu" "F.Mask" "F.Paste")
			(net "M_A_CPU0_SA_PAR")
		)
		(pad "BC74" smd circle
			(at 33.519872 -2.789936 180)
			(size 0.450088 0.450088)
			(layers "F.Cu" "F.Mask" "F.Paste")
			(net "M_A_CPU0_CLK_DP<0>")
		)
		(pad "BC75" smd circle
			(at 34.459926 -2.789936 180)
			(size 0.450088 0.450088)
			(layers "F.Cu" "F.Mask" "F.Paste")
			(net "GND")
		)
		(pad "BD2" smd circle
			(at -33.690052 -1.97993 180)
			(size 0.450088 0.450088)
			(layers "F.Cu" "F.Mask" "F.Paste")
			(net "M_G_CPU0_CLK_DN<0>")
		)
		(pad "BD3" smd circle
			(at -32.749998 -1.97993 180)
			(size 0.450088 0.450088)
			(layers "F.Cu" "F.Mask" "F.Paste")
			(net "GND")
		)
		(pad "BD4" smd circle
			(at -31.809944 -1.97993 180)
			(size 0.450088 0.450088)
			(layers "F.Cu" "F.Mask" "F.Paste")
			(net "Net_1917")
		)
		(pad "BD5" smd circle
			(at -30.86989 -1.97993 180)
			(size 0.450088 0.450088)
			(layers "F.Cu" "F.Mask" "F.Paste")
			(net "PVDDCR_SOC_P0")
		)
		(pad "BD6" smd circle
			(at -29.93009 -1.97993 180)
			(size 0.450088 0.450088)
			(layers "F.Cu" "F.Mask" "F.Paste")
			(net "M_K_CPU0_CLK_DN<0>")
		)
		(pad "BD7" smd circle
			(at -28.990036 -1.97993 180)
			(size 0.450088 0.450088)
			(layers "F.Cu" "F.Mask" "F.Paste")
			(net "Net_1923")
		)
		(pad "BD8" smd circle
			(at -28.049982 -1.97993 180)
			(size 0.450088 0.450088)
			(layers "F.Cu" "F.Mask" "F.Paste")
			(net "GND")
		)
		(pad "BD9" smd circle
			(at -27.109928 -1.97993 180)
			(size 0.450088 0.450088)
			(layers "F.Cu" "F.Mask" "F.Paste")
			(net "M_L_CPU0_CLK_DN<0>")
		)
		(pad "BD10" smd circle
			(at -26.170128 -1.97993 180)
			(size 0.450088 0.450088)
			(layers "F.Cu" "F.Mask" "F.Paste")
			(net "GND")
		)
		(pad "BD11" smd circle
			(at -25.230074 -1.97993 180)
			(size 0.450088 0.450088)
			(layers "F.Cu" "F.Mask" "F.Paste")
			(net "Net_1913")
		)
		(pad "BD12" smd circle
			(at -24.29002 -1.97993 180)
			(size 0.450088 0.450088)
			(layers "F.Cu" "F.Mask" "F.Paste")
			(net "PVDDCR_SOC_P0")
		)
		(pad "BD13" smd circle
			(at -23.349966 -1.97993 180)
			(size 0.450088 0.450088)
			(layers "F.Cu" "F.Mask" "F.Paste")
			(net "M_H_CPU0_CLK_DN<0>")
		)
		(pad "BD14" smd circle
			(at -22.409912 -1.97993 180)
			(size 0.450088 0.450088)
			(layers "F.Cu" "F.Mask" "F.Paste")
			(net "Net_1914")
		)
		(pad "BD15" smd circle
			(at -21.470112 -1.97993 180)
			(size 0.450088 0.450088)
			(layers "F.Cu" "F.Mask" "F.Paste")
			(net "GND")
		)
		(pad "BD16" smd circle
			(at -20.530058 -1.97993 180)
			(size 0.450088 0.450088)
			(layers "F.Cu" "F.Mask" "F.Paste")
			(net "M_J_CPU0_CLK_DN<0>")
		)
		(pad "BD17" smd circle
			(at -19.590004 -1.97993 180)
			(size 0.450088 0.450088)
			(layers "F.Cu" "F.Mask" "F.Paste")
			(net "GND")
		)
		(pad "BD18" smd circle
			(at -18.64995 -1.97993 180)
			(size 0.450088 0.450088)
			(layers "F.Cu" "F.Mask" "F.Paste")
			(net "Net_1915")
		)
		(pad "BD19" smd circle
			(at -17.709896 -1.97993 180)
			(size 0.450088 0.450088)
			(layers "F.Cu" "F.Mask" "F.Paste")
			(net "PVDDCR_SOC_P0")
		)
		(pad "BD20" smd circle
			(at -16.770096 -1.97993 180)
			(size 0.450088 0.450088)
			(layers "F.Cu" "F.Mask" "F.Paste")
			(net "M_I_CPU0_CLK_DN<0>")
		)
		(pad "BD21" smd circle
			(at -15.830042 -1.97993 180)
			(size 0.450088 0.450088)
			(layers "F.Cu" "F.Mask" "F.Paste")
			(net "Net_1916")
		)
		(pad "BD22" smd circle
			(at -14.889988 -1.97993 180)
			(size 0.450088 0.450088)
			(layers "F.Cu" "F.Mask" "F.Paste")
			(net "PVDDCR_SOC_P0")
		)
		(pad "BD23" smd circle
			(at -13.949934 -1.97993 180)
			(size 0.450088 0.450088)
			(layers "F.Cu" "F.Mask" "F.Paste")
			(net "GND")
		)
		(pad "BD24" smd circle
			(at -13.00988 -1.97993 180)
			(size 0.450088 0.450088)
			(layers "F.Cu" "F.Mask" "F.Paste")
			(net "PVDDCR_SOC_P0")
		)
		(pad "BD25" smd circle
			(at -12.07008 -1.97993 180)
			(size 0.450088 0.450088)
			(layers "F.Cu" "F.Mask" "F.Paste")
			(net "GND")
		)
		(pad "BD26" smd circle
			(at -11.130026 -1.97993 180)
			(size 0.450088 0.450088)
			(layers "F.Cu" "F.Mask" "F.Paste")
			(net "PVDDCR_SOC_P0")
		)
		(pad "BD27" smd circle
			(at -10.189972 -1.97993 180)
			(size 0.450088 0.450088)
			(layers "F.Cu" "F.Mask" "F.Paste")
			(net "GND")
		)
		(pad "BD28" smd circle
			(at -9.249918 -1.97993 180)
			(size 0.450088 0.450088)
			(layers "F.Cu" "F.Mask" "F.Paste")
			(net "PVDDCR_SOC_P0")
		)
		(pad "BD48" smd circle
			(at 9.549892 -1.97993 180)
			(size 0.450088 0.450088)
			(layers "F.Cu" "F.Mask" "F.Paste")
			(net "PVDDCR_SOC_P0")
		)
		(pad "BD49" smd circle
			(at 10.489946 -1.97993 180)
			(size 0.450088 0.450088)
			(layers "F.Cu" "F.Mask" "F.Paste")
			(net "GND")
		)
		(pad "BD50" smd circle
			(at 11.43 -1.97993 180)
			(size 0.450088 0.450088)
			(layers "F.Cu" "F.Mask" "F.Paste")
			(net "PVDDIO_P0")
		)
		(pad "BD51" smd circle
			(at 12.370054 -1.97993 180)
			(size 0.450088 0.450088)
			(layers "F.Cu" "F.Mask" "F.Paste")
			(net "GND")
		)
		(pad "BD52" smd circle
			(at 13.310108 -1.97993 180)
			(size 0.450088 0.450088)
			(layers "F.Cu" "F.Mask" "F.Paste")
			(net "PVDDIO_P0")
		)
		(pad "BD53" smd circle
			(at 14.249908 -1.97993 180)
			(size 0.450088 0.450088)
			(layers "F.Cu" "F.Mask" "F.Paste")
			(net "GND")
		)
		(pad "BD54" smd circle
			(at 15.189962 -1.97993 180)
			(size 0.450088 0.450088)
			(layers "F.Cu" "F.Mask" "F.Paste")
			(net "PVDDIO_P0")
		)
		(pad "BD55" smd circle
			(at 16.130016 -1.97993 180)
			(size 0.450088 0.450088)
			(layers "F.Cu" "F.Mask" "F.Paste")
			(net "Net_1918")
		)
		(pad "BD56" smd circle
			(at 17.07007 -1.97993 180)
			(size 0.450088 0.450088)
			(layers "F.Cu" "F.Mask" "F.Paste")
			(net "M_C_CPU0_CLK_DN<0>")
		)
		(pad "BD57" smd circle
			(at 18.010124 -1.97993 180)
			(size 0.450088 0.450088)
			(layers "F.Cu" "F.Mask" "F.Paste")
			(net "GND")
		)
		(pad "BD58" smd circle
			(at 18.949924 -1.97993 180)
			(size 0.450088 0.450088)
			(layers "F.Cu" "F.Mask" "F.Paste")
			(net "Net_1919")
		)
		(pad "BD59" smd circle
			(at 19.889978 -1.97993 180)
			(size 0.450088 0.450088)
			(layers "F.Cu" "F.Mask" "F.Paste")
			(net "GND")
		)
		(pad "BD60" smd circle
			(at 20.830032 -1.97993 180)
			(size 0.450088 0.450088)
			(layers "F.Cu" "F.Mask" "F.Paste")
			(net "M_D_CPU0_CLK_DN<0>")
		)
		(pad "BD61" smd circle
			(at 21.770086 -1.97993 180)
			(size 0.450088 0.450088)
			(layers "F.Cu" "F.Mask" "F.Paste")
			(net "GND")
		)
		(pad "BD62" smd circle
			(at 22.709886 -1.97993 180)
			(size 0.450088 0.450088)
			(layers "F.Cu" "F.Mask" "F.Paste")
			(net "Net_1920")
		)
		(pad "BD63" smd circle
			(at 23.64994 -1.97993 180)
			(size 0.450088 0.450088)
			(layers "F.Cu" "F.Mask" "F.Paste")
			(net "M_B_CPU0_CLK_DN<0>")
		)
		(pad "BD64" smd circle
			(at 24.589994 -1.97993 180)
			(size 0.450088 0.450088)
			(layers "F.Cu" "F.Mask" "F.Paste")
			(net "GND")
		)
		(pad "BD65" smd circle
			(at 25.530048 -1.97993 180)
			(size 0.450088 0.450088)
			(layers "F.Cu" "F.Mask" "F.Paste")
			(net "Net_1921")
		)
		(pad "BD66" smd circle
			(at 26.470102 -1.97993 180)
			(size 0.450088 0.450088)
			(layers "F.Cu" "F.Mask" "F.Paste")
			(net "GND")
		)
		(pad "BD67" smd circle
			(at 27.409902 -1.97993 180)
			(size 0.450088 0.450088)
			(layers "F.Cu" "F.Mask" "F.Paste")
			(net "M_F_CPU0_CLK_DN<0>")
		)
		(pad "BD68" smd circle
			(at 28.349956 -1.97993 180)
			(size 0.450088 0.450088)
			(layers "F.Cu" "F.Mask" "F.Paste")
			(net "GND")
		)
		(pad "BD69" smd circle
			(at 29.29001 -1.97993 180)
			(size 0.450088 0.450088)
			(layers "F.Cu" "F.Mask" "F.Paste")
			(net "Net_1922")
		)
		(pad "BD70" smd circle
			(at 30.230064 -1.97993 180)
			(size 0.450088 0.450088)
			(layers "F.Cu" "F.Mask" "F.Paste")
			(net "M_E_CPU0_CLK_DN<0>")
		)
		(pad "BD71" smd circle
			(at 31.170118 -1.97993 180)
			(size 0.450088 0.450088)
			(layers "F.Cu" "F.Mask" "F.Paste")
			(net "GND")
		)
		(pad "BD72" smd circle
			(at 32.109918 -1.97993 180)
			(size 0.450088 0.450088)
			(layers "F.Cu" "F.Mask" "F.Paste")
			(net "Net_1924")
		)
		(pad "BD73" smd circle
			(at 33.049972 -1.97993 180)
			(size 0.450088 0.450088)
			(layers "F.Cu" "F.Mask" "F.Paste")
			(net "GND")
		)
		(pad "BD74" smd circle
			(at 33.990026 -1.97993 180)
			(size 0.450088 0.450088)
			(layers "F.Cu" "F.Mask" "F.Paste")
			(net "M_A_CPU0_CLK_DN<0>")
		)
		(pad "BF2" smd circle
			(at -33.990026 1.97993 180)
			(size 0.450088 0.450088)
			(layers "F.Cu" "F.Mask" "F.Paste")
			(net "Net_1835")
		)
		(pad "BF3" smd circle
			(at -33.049972 1.97993 180)
			(size 0.450088 0.450088)
			(layers "F.Cu" "F.Mask" "F.Paste")
			(net "GND")
		)
	)
)
